FILE_TYPE = CONNECTIVITY;
{Allegro Design Entry HDL 17.2-2016 S081 (4005846) 1/11/2022}
"PAGE_NUMBER" = 214;
0"NC";
1"P3V3_AUX\g"VOLTAGE"3.3";
2"P3V3_AUX\g";
3"P3V3_AUX\g";
4"P3V3_AUX\g";
5"GND\g";
6"GND\g";
7"GND\g";
8"GND\g";
9"PRSNT_CABLE_GPU_A3_ISO_N";
10"PRSNT_CABLE_GPU_A3_ISO_R_N";
11"PRSNT_CABLE_GPU_A3_ISO_R_N";
12"PRSNT_CABLE_GPU_A1_ISO_R1_N"CDS_PHYS_NET_NAME"CLK_25M_OSC_FPGA_R";
13"PRSNT_CABLE_SWB_B2_ISO_R_N";
14"GPU_PRSNT_N_ISO_R1"CDS_PHYS_NET_NAME"FM_GPU_POWER_EN_R";
15"PRSNT_SWB_ISO_R1_N"CDS_PHYS_NET_NAME"FM_GPU_POWER_EN_R";
16"SMB_IOEXP_3V3AUX_SDA_R1"CDS_PHYS_NET_NAME"RST_MB_BMC_RST_BIC_R";
17"SMB_IOEXP_3V3AUX_SCL_R1"CDS_PHYS_NET_NAME"FM_GPU_POWER_EN_R";
18"RST_SWB_BIC_R_N"CDS_PHYS_NET_NAME"FM_GPU_POWER_EN_R";
19"SMB_IOEXP_3V3AUX_SDA_R1"CDS_PHYS_NET_NAME"SMB_PEHPCPU1_LVC3_R2_SCL";
20"SMB_IOEXP_3V3AUX_SCL_R1"CDS_PHYS_NET_NAME"SMB_PEHPCPU1_LVC3_R2_SDA";
21"TCA9539_0_ADD0"$PHYS_NET_NAME"RST_PCIE_M2_N"CDS_PHYS_NET_NAME"TP_PCA9555_2_P17";
22"GPU_PEX_STRAP1_R"$PHYS_NET_NAME"RST_PCIE_M2_N"CDS_PHYS_NET_NAME"TP_PCA9555_2_P15";
23"PRSNT_SWB_ISO_N"CDS_PHYS_NET_NAME"FM_GPU_POWER_EN";
24"GPU_PRSNT_N_ISO"CDS_PHYS_NET_NAME"FM_GPU_POWER_EN";
25"PRSNT_CABLE_SWB_B1_ISO_N";
26"PRSNT_CABLE_GPU_A1_ISO_N"CDS_PHYS_NET_NAME"CLK_25M_OSC_FPGA_R";
27"PRSNT_CABLE_GPU_B3_ISO_R1_N"CDS_PHYS_NET_NAME"FM_GPU_POWER_EN_R";
28"PRSNT_CABLE_GPU_B3_ISO_N"CDS_PHYS_NET_NAME"FM_GPU_POWER_EN";
29"PRSNT_CABLE_SWB_B2_ISO_N";
30"PRSNT_CABLE_GPU_A2_ISO_N";
31"GPU_PEX_STRAP0_R"CDS_PHYS_NET_NAME"FM_GPU_SMB2_ALERT_BUF_R_N";
32"GPU_BASE_ID0_R"CDS_PHYS_NET_NAME"RST_MB_BMC_RST_BIC_R";
33"GPU_PEX_STRAP0"CDS_PHYS_NET_NAME"FM_GPU_SMB2_ALERT_BUF_N";
34"GPU_PEX_STRAP1"CDS_PHYS_NET_NAME"FM_GPU_SMB1_ALERT_BUF_N";
35"GPU_BASE_ID0"CDS_PHYS_NET_NAME"RST_MB_BMC_RST_BIC";
36"PRSNT_CABLE_GPU_A1_ISO_R1_N"$PHYS_NET_NAME"RST_PCIE_M2_N"CDS_PHYS_NET_NAME"TP_PCA9555_2_P16";
37"PRSNT_CABLE_SWB_B2_ISO_R_N"$PHYS_NET_NAME"RST_PCIE_M2_N"CDS_PHYS_NET_NAME"TP_PCA9555_2_P17";
38"PRSNT_CABLE_GPU_B3_ISO_R1_N"$PHYS_NET_NAME"RST_PCIE_M2_N"CDS_PHYS_NET_NAME"TP_PCA9555_2_P16";
39"GPU_PRSNT_N_ISO_R1"$PHYS_NET_NAME"RST_PCIE_M2_N"CDS_PHYS_NET_NAME"TP_TCA9539_0_P0_7";
40"PRSNT_SWB_ISO_R1_N"$PHYS_NET_NAME"RST_PCIE_M2_N"CDS_PHYS_NET_NAME"TP_TCA9539_0_P0_6";
41"TP_TCA9539_0_P0_3"$PHYS_NET_NAME"RST_PCIE_M2_N"CDS_PHYS_NET_NAME"TP_PCA9555_2_P17";
42"TP_TCA9539_0_P0_2"$PHYS_NET_NAME"RST_PCIE_M2_N"CDS_PHYS_NET_NAME"TP_PCA9555_2_P16";
43"GPU_PEX_STRAP1_R"CDS_PHYS_NET_NAME"FM_GPU_SMB1_ALERT_BUF_R_N";
44"PRSNT_CABLE_SWB_B1_ISO_R_N";
45"GPU_BASE_ID1"CDS_PHYS_NET_NAME"FM_GPU_POWER_EN";
46"SMB_IOEXP_3V3AUX_SDA"CDS_PHYS_NET_NAME"RST_MB_BMC_RST_BIC";
47"SMB_IOEXP_3V3AUX_SCL"CDS_PHYS_NET_NAME"FM_GPU_POWER_EN";
48"RST_SWB_BIC_N"CDS_PHYS_NET_NAME"FM_GPU_POWER_EN";
49"PRSNT_CABLE_GPU_A2_ISO_R1_N";
50"GPU_BASE_ID1_R"CDS_PHYS_NET_NAME"FM_GPU_POWER_EN_R";
51"TCA9539_0_ADD1"$PHYS_NET_NAME"RST_PCIE_M2_N"CDS_PHYS_NET_NAME"TP_PCA9555_2_P00";
52"PRSNT_CABLE_GPU_A2_ISO_R1_N"$PHYS_NET_NAME"RST_PCIE_M2_N"CDS_PHYS_NET_NAME"TP_PCA9555_2_P16";
53"PRSNT_CABLE_SWB_B1_ISO_R_N"$PHYS_NET_NAME"RST_PCIE_M2_N"CDS_PHYS_NET_NAME"TP_PCA9555_2_P17";
54"GPU_BASE_ID0_R"$PHYS_NET_NAME"RST_PCIE_M2_N"CDS_PHYS_NET_NAME"E1S_7_BUF_EN";
55"TCA9539_0_ADD0"CDS_PHYS_NET_NAME"PCA9555_2_ADD0";
56"TCA9539_0_ADD1"CDS_PHYS_NET_NAME"PCA9555_2_ADD1";
57"PU_U181_INT";
58"GPU_BASE_ID1_R"$PHYS_NET_NAME"RST_PCIE_M2_N"CDS_PHYS_NET_NAME"TP_PCA9555_2_P13";
59"RST_SMB_SWITCH_N"CDS_PHYS_NET_NAME"RST_SMB_SWITCH_N";
60"GPU_PEX_STRAP0_R"$PHYS_NET_NAME"RST_PCIE_M2_N"CDS_PHYS_NET_NAME"E1S_7_BUF_PRSNT_N";
61"RST_SWB_BIC_N"$PHYS_NET_NAME"RST_PCIE_M2_N"CDS_PHYS_NET_NAME"RST_SWB_BIC_N";
62"PU_RST_SMB_U181_N"CDS_PHYS_NET_NAME"PU_RST_SMB_PCIE0_N";
63"RST_USB_HUB_N"$PHYS_NET_NAME"RST_PCIE_M2_N"CDS_PHYS_NET_NAME"RST_USB_HUB_N";
%"Q_RES"
"1","(8675,3325)","0","pure_quanta","I101";
;
PART_NUMBER"CS00002JB13"
MATERIAL"CHIP"
TOLERANCE"5%"
VALUE"0"
$LOCATION"R2983"
WATTAGE"1/16W"
PACK_TYPE"0402LF"
CDS_LIB"pure_quanta"
CDS_LOCATION"R2983"
$SEC"1"
CDS_SEC"1";
"B"
$PN"2"16;
"A"
$PN"1"46;
%"Q_RES"
"1","(8675,3125)","0","pure_quanta","I118";
;
PART_NUMBER"CS00002JB13"
MATERIAL"CHIP"
TOLERANCE"5%"
VALUE"0"
$LOCATION"R3499"
CDS_LIB"pure_quanta"
PACK_TYPE"0402LF"
WATTAGE"1/16W"
CDS_LOCATION"R3499"
$SEC"1"
CDS_SEC"1";
"B"
$PN"2"50;
"A"
$PN"1"45;
%"Q_RES"
"1","(8675,2925)","0","pure_quanta","I127";
;
PART_NUMBER"CS00002JB13"
TOLERANCE"5%"
VALUE"0"
MATERIAL"CHIP"
$LOCATION"R3516"
WATTAGE"1/16W"
PACK_TYPE"0402LF"
CDS_LIB"pure_quanta"
CDS_LOCATION"R3516"
$SEC"1"
CDS_SEC"1";
"B"
$PN"2"32;
"A"
$PN"1"35;
%"Q_RES"
"1","(8675,2725)","0","pure_quanta","I128";
;
PART_NUMBER"CS00002JB13"
VALUE"0"
TOLERANCE"5%"
MATERIAL"CHIP"
$LOCATION"R3517"
PACK_TYPE"0402LF"
WATTAGE"1/16W"
CDS_LIB"pure_quanta"
CDS_LOCATION"R3517"
$SEC"1"
CDS_SEC"1";
"B"
$PN"2"43;
"A"
$PN"1"34;
%"Q_RES"
"1","(8675,2525)","0","pure_quanta","I129";
;
PART_NUMBER"CS00002JB13"
MATERIAL"CHIP"
TOLERANCE"5%"
VALUE"0"
$LOCATION"R3518"
PACK_TYPE"0402LF"
WATTAGE"1/16W"
CDS_LIB"pure_quanta"
CDS_LOCATION"R3518"
$SEC"1"
CDS_SEC"1";
"B"
$PN"2"31;
"A"
$PN"1"33;
%"Q_RES"
"1","(8650,2200)","0","pure_quanta","I137";
;
PART_NUMBER"CS00002JB13"
MATERIAL"CHIP"
TOLERANCE"5%"
VALUE"0"
$LOCATION"R4728"
WATTAGE"1/16W"
PACK_TYPE"0402LF"
CDS_LIB"pure_quanta"
CDS_LOCATION"R4728"
$SEC"1"
CDS_SEC"1";
"B"
$PN"2"15;
"A"
$PN"1"23;
%"Q_RES"
"1","(8650,2050)","0","pure_quanta","I140";
;
PART_NUMBER"CS00002JB13"
VALUE"0"
MATERIAL"CHIP"
TOLERANCE"5%"
$LOCATION"R4729"
CDS_LIB"pure_quanta"
PACK_TYPE"0402LF"
WATTAGE"1/16W"
CDS_LOCATION"R4729"
$SEC"1"
CDS_SEC"1";
"B"
$PN"2"14;
"A"
$PN"1"24;
%"Q_RES"
"1","(8650,1900)","0","pure_quanta","I144";
;
PART_NUMBER"CS00002JB13"
MATERIAL"CHIP"
TOLERANCE"5%"
VALUE"0"
$LOCATION"R4734"
WATTAGE"1/16W"
PACK_TYPE"0402LF"
CDS_LIB"pure_quanta"
CDS_LOCATION"R4734"
$SEC"1"
CDS_SEC"1";
"B"
$PN"2"27;
"A"
$PN"1"28;
%"Q_RES"
"1","(8650,1750)","0","pure_quanta","I148";
;
PART_NUMBER"CS00002JB13"
MATERIAL"CHIP"
TOLERANCE"5%"
VALUE"0"
$LOCATION"R4735"
WATTAGE"1/16W"
PACK_TYPE"0402LF"
CDS_LIB"pure_quanta"
CDS_LOCATION"R4735"
$SEC"1"
CDS_SEC"1";
"B"
$PN"2"13;
"A"
$PN"1"29;
%"Q_RES"
"1","(8650,1600)","0","pure_quanta","I153";
;
PART_NUMBER"CS00002JB13"
MATERIAL"CHIP"
TOLERANCE"5%"
VALUE"0"
$LOCATION"R4736"
PACK_TYPE"0402LF"
WATTAGE"1/16W"
CDS_LIB"pure_quanta"
CDS_LOCATION"R4736"
$SEC"1"
CDS_SEC"1";
"B"
$PN"2"49;
"A"
$PN"1"30;
%"Q_RES"
"1","(8650,1450)","0","pure_quanta","I156";
;
PART_NUMBER"CS00002JB13"
TOLERANCE"5%"
MATERIAL"CHIP"
VALUE"0"
$LOCATION"R4741"
PACK_TYPE"0402LF"
WATTAGE"1/16W"
CDS_LIB"pure_quanta"
CDS_LOCATION"R4741"
$SEC"1"
CDS_SEC"1";
"B"
$PN"2"44;
"A"
$PN"1"25;
%"Q_RES"
"1","(8650,1300)","0","pure_quanta","I161";
;
PART_NUMBER"CS00002JB13"
VALUE"0"
TOLERANCE"5%"
MATERIAL"CHIP"
$LOCATION"R4742"
PACK_TYPE"0402LF"
WATTAGE"1/16W"
CDS_LIB"pure_quanta"
CDS_LOCATION"R4742"
$SEC"1"
CDS_SEC"1";
"B"
$PN"2"12;
"A"
$PN"1"26;
%"Q_RES"
"1","(8650,975)","0","pure_quanta","I164";
;
PART_NUMBER"CS00002JB13"
MATERIAL"CHIP"
TOLERANCE"5%"
VALUE"0"
$LOCATION"R4802"
WATTAGE"1/16W"
PACK_TYPE"0402LF"
CDS_LIB"pure_quanta"
CDS_LOCATION"R4802"
$SEC"1"
CDS_SEC"1";
"B"
$PN"2"10;
"A"
$PN"1"9;
%"Q_RES"
"1","(8675,3750)","0","pure_quanta","I34";
;
PART_NUMBER"CS00002JB13"
MATERIAL"CHIP"
TOLERANCE"5%"
VALUE"0"
$LOCATION"R2848"
WATTAGE"1/16W"
PACK_TYPE"0402LF"
CDS_LIB"pure_quanta"
CDS_LOCATION"R2848"
$SEC"1"
CDS_SEC"1";
"B"
$PN"2"18;
"A"
$PN"1"48;
%"PCA9539RPW"
"1","(7875,5200)","0","pure_quanta","I66";
;
PART_NUMBER"AL009539K07"
PART_TYPE"SMLF"
VALUE"PCA9539RPW"
MATERIAL"IC"
LOCATION"U181"
SEC_TYPE""
CDS_LIB"pure_quanta"
NEEDS_NO_SIZE"TRUE"
CDS_LMAN_SYM_OUTLINE"-250,600,250,-600"
SEC"1";
"VDD"
$PN"24"1;
"SDA"
$PN"23"19;
"SCL"
$PN"22"20;
"A0"
$PN"21"21;
"IO1_7"
$PN"20"11;
"IO1_6"
$PN"19"36;
"IO1_5"
$PN"18"22;
"IO1_4"
$PN"17"60;
"IO1_3"
$PN"16"58;
"IO1_2"
$PN"15"54;
"IO1_1"
$PN"14"53;
"IO1_0"
$PN"13"52;
"VSS"
$PN"12"5;
"IO0_7"
$PN"11"37;
"IO0_6"
$PN"10"38;
"IO0_5"
$PN"9"39;
"IO0_4"
$PN"8"40;
"IO0_3"
$PN"7"41;
"IO0_2"
$PN"6"42;
"IO0_1"
$PN"5"61;
"IO0_0"
$PN"4"63;
"RESET \B"
$PN"3"62;
"A1"
$PN"2"51;
"INT \B"
$PN"1"57;
%"UNIVERSAL_POWER"
"1","(5100,3775)","0","logical_power","I73";
;
HDL_POWER"P3V3_AUX"
CDS_LIB"logical_power";
"A"4;
%"Q_RES"
"2","(5350,3375)","0","pure_quanta","I74";
;
PART_NUMBER"CS21002FB06"
WATTAGE"1/16W"
VALUE"1K"
PACK_TYPE"0402LF"
TOLERANCE"1%"
MATERIAL"EMPTY"
$LOCATION"R2695"
CDS_LIB"pure_quanta"
CDS_LOCATION"R2695"
$SEC"1"
CDS_SEC"1";
"A"
$PN"1"4;
"B"
$PN"2"55;
%"Q_RES"
"2","(5350,2775)","0","pure_quanta","I75";
;
PART_NUMBER"CS21002FB06"
MATERIAL"CHIP"
PACK_TYPE"0402LF"
WATTAGE"1/16W"
VALUE"1K"
TOLERANCE"1%"
$LOCATION"R2696"
CDS_LIB"pure_quanta"
CDS_LOCATION"R2696"
$SEC"1"
CDS_SEC"1";
"A"
$PN"1"55;
"B"
$PN"2"7;
%"Q_RES"
"2","(5100,3375)","0","pure_quanta","I76";
;
PART_NUMBER"CS21002FB06"
TOLERANCE"1%"
WATTAGE"1/16W"
VALUE"1K"
MATERIAL"EMPTY"
PACK_TYPE"0402LF"
$LOCATION"R2693"
CDS_LIB"pure_quanta"
CDS_LOCATION"R2693"
$SEC"1"
CDS_SEC"1";
"A"
$PN"1"4;
"B"
$PN"2"56;
%"Q_RES"
"2","(5100,2775)","0","pure_quanta","I77";
;
PART_NUMBER"CS21002FB06"
MATERIAL"CHIP"
PACK_TYPE"0402LF"
VALUE"1K"
WATTAGE"1/16W"
TOLERANCE"1%"
$LOCATION"R2694"
CDS_LIB"pure_quanta"
CDS_LOCATION"R2694"
$SEC"1"
CDS_SEC"1";
"A"
$PN"1"56;
"B"
$PN"2"8;
%"UNIVERSAL_GND"
"1","(5350,2550)","0","logical_power","I78";
;
CDS_LIB"logical_power"
HDL_POWER"GND";
"A"7;
%"UNIVERSAL_GND"
"1","(5100,2550)","0","logical_power","I79";
;
CDS_LIB"logical_power"
HDL_POWER"GND";
"A"8;
%"UNIVERSAL_GND"
"1","(7325,4425)","0","logical_power","I86";
;
CDS_LIB"logical_power"
HDL_POWER"GND";
"A"5;
%"Q_CAP"
"1","(9000,4150)","2","pure_quanta","I87";
;
PART_NUMBER"CH4104K1B00"
VALUE"0.1UF"
PACK_TYPE"0402"
MATERIAL"X7R"
TOLERANCE"10%"
VOLTAGE"25V"
$LOCATION"C1713"
CDS_LIB"pure_quanta"
CDS_LOCATION"C1713"
$SEC"1"
CDS_SEC"1";
"B"
$PN"2"6;
"A"
$PN"1"1;
%"UNIVERSAL_POWER"
"1","(9000,4425)","0","logical_power","I88";
;
HDL_POWER"P3V3_AUX"
CDS_LIB"logical_power";
"A"1;
%"UNIVERSAL_GND"
"1","(9000,3925)","0","logical_power","I89";
;
HDL_POWER"GND"
CDS_LIB"logical_power";
"A"6;
%"Q_RES"
"2","(6675,6050)","0","pure_quanta","I90";
;
PART_NUMBER"CS24702JB10"
PACK_TYPE"0402LF"
TOLERANCE"5%"
WATTAGE"1/16W"
VALUE"4.7K"
MATERIAL"EMPTY"
$LOCATION"R2923"
CDS_LIB"pure_quanta"
CDS_LOCATION"R2923"
$SEC"1"
CDS_SEC"1";
"A"
$PN"1"2;
"B"
$PN"2"57;
%"UNIVERSAL_POWER"
"1","(6675,6275)","0","logical_power","I91";
;
HDL_POWER"P3V3_AUX"
CDS_LIB"logical_power";
"A"2;
%"Q_RES"
"2","(5900,5925)","2","pure_quanta","I93";
;
PART_NUMBER"CS31002FB08"
VALUE"10K"
WATTAGE"1/16W"
TOLERANCE"1%"
PACK_TYPE"0402LF"
MATERIAL"EMPTY"
$LOCATION"R2921"
CDS_LIB"pure_quanta"
CDS_LOCATION"R2921"
$SEC"1"
CDS_SEC"1";
"A"
$PN"1"3;
"B"
$PN"2"59;
%"UNIVERSAL_POWER"
"1","(5900,6200)","0","logical_power","I94";
;
HDL_POWER"P3V3_AUX"
CDS_LIB"logical_power";
"A"3;
%"Q_RES"
"1","(6250,5550)","0","pure_quanta","I95";
;
PART_NUMBER"CS00002JB13"
VALUE"0"
MATERIAL"CHIP"
TOLERANCE"5%"
$LOCATION"R2922"
CDS_LIB"pure_quanta"
WATTAGE"1/16W"
PACK_TYPE"0402LF"
CDS_LOCATION"R2922"
$SEC"1"
CDS_SEC"1";
"B"
$PN"2"62;
"A"
$PN"1"59;
%"Q_RES"
"1","(8675,3525)","0","pure_quanta","I96";
;
PART_NUMBER"CS00002JB13"
MATERIAL"CHIP"
TOLERANCE"5%"
VALUE"0"
$LOCATION"R2982"
CDS_LIB"pure_quanta"
PACK_TYPE"0402LF"
WATTAGE"1/16W"
CDS_LOCATION"R2982"
$SEC"1"
CDS_SEC"1";
"B"
$PN"2"17;
"A"
$PN"1"47;
END.
